(kicad_pcb
	(version 20260206)
	(generator "pcbnew")
	(generator_version "10.0")
	(general
		(thickness 1.6)
		(legacy_teardrops no)
	)
	(paper "A4")
	(title_block
		(title "04192023_DAF0TMB3IC0_F0TG_MB_C_brd_V02_OCP.brd")
		(comment 1 "Grand Teton / footprints 2601-2605 of 8354")
	)
	(layers
		(0 "F.Cu" signal "TOP")
		(4 "In1.Cu" signal "GND")
		(6 "In2.Cu" signal "IN1")
		(8 "In3.Cu" signal "GND1")
		(10 "In4.Cu" signal "IN2")
		(12 "In5.Cu" signal "GND2")
		(14 "In6.Cu" signal "IN3")
		(16 "In7.Cu" signal "GND3")
		(18 "In8.Cu" signal "VCC")
		(20 "In9.Cu" signal "VCC1")
		(22 "In10.Cu" signal "GND4")
		(24 "In11.Cu" signal "IN4")
		(26 "In12.Cu" signal "GND5")
		(28 "In13.Cu" signal "IN5")
		(30 "In14.Cu" signal "GND6")
		(32 "In15.Cu" signal "IN6")
		(34 "In16.Cu" signal "GND7")
		(2 "B.Cu" signal "BOTTOM")
		(9 "F.Adhes" user "F.Adhesive")
		(11 "B.Adhes" user "B.Adhesive")
		(13 "F.Paste" user "Package Geometry/Pastemask Top")
		(15 "B.Paste" user "Package Geometry/Pastemask Bottom")
		(5 "F.SilkS" user "Ref Des/Silkscreen Top")
		(7 "B.SilkS" user "Ref Des/Silkscreen Bottom")
		(1 "F.Mask" user "Board Geometry/Soldermask Top")
		(3 "B.Mask" user "Board Geometry/Soldermask Bottom")
		(17 "Dwgs.User" user "User.Drawings")
		(19 "Cmts.User" user "User.Comments")
		(21 "Eco1.User" user "User.Eco1")
		(23 "Eco2.User" user "User.Eco2")
		(25 "Edge.Cuts" user "Board Geometry/Outline")
		(27 "Margin" user)
		(31 "F.CrtYd" user "Package Geometry/Place Bound Top")
		(29 "B.CrtYd" user "Package Geometry/Place Bound Bottom")
		(35 "F.Fab" user "Ref Des/Assembly Top")
		(33 "B.Fab" user "Ref Des/Assembly Bottom")
	)
	(footprint ""
		(layer "F.Cu")
		(at 232.732072 -69.560186 90)
		(property "Reference" "R1000"
			(at 0 0 90)
			(layer "F.SilkS")
			(hide yes)
			(effects
				(font
					(size 1.27 1.27)
				)
			)
		)
		(property "Value" ""
			(at 0 0 90)
			(layer "F.Fab")
			(effects
				(font
					(size 1.27 1.27)
				)
			)
		)
		(duplicate_pad_numbers_are_jumpers no)
		(fp_line
			(start 0.7874 -0.4064)
			(end 0.7874 0.4064)
			(stroke
				(width 0.1524)
				(type default)
			)
			(layer "F.SilkS")
		)
		(fp_line
			(start -0.7874 -0.4064)
			(end 0.7874 -0.4064)
			(stroke
				(width 0.1524)
				(type default)
			)
			(layer "F.SilkS")
		)
		(fp_line
			(start 0.7874 0.4064)
			(end -0.7874 0.4064)
			(stroke
				(width 0.1524)
				(type default)
			)
			(layer "F.SilkS")
		)
		(fp_line
			(start -0.7874 0.4064)
			(end -0.7874 -0.4064)
			(stroke
				(width 0.1524)
				(type default)
			)
			(layer "F.SilkS")
		)
		(fp_line
			(start -0.12065 -0.305054)
			(end -0.12065 -0.2794)
			(stroke
				(width 0.1)
				(type default)
			)
			(layer "F.Fab")
		)
		(fp_line
			(start -0.67945 -0.305054)
			(end -0.12065 -0.305054)
			(stroke
				(width 0.1)
				(type default)
			)
			(layer "F.Fab")
		)
		(fp_line
			(start 0.67945 -0.3048)
			(end 0.67945 0.3048)
			(stroke
				(width 0.1)
				(type default)
			)
			(layer "F.Fab")
		)
		(fp_line
			(start 0.12065 -0.3048)
			(end 0.67945 -0.3048)
			(stroke
				(width 0.1)
				(type default)
			)
			(layer "F.Fab")
		)
		(fp_line
			(start 0.12065 -0.2794)
			(end 0.12065 -0.3048)
			(stroke
				(width 0.1)
				(type default)
			)
			(layer "F.Fab")
		)
		(fp_line
			(start -0.12065 -0.2794)
			(end 0.12065 -0.2794)
			(stroke
				(width 0.1)
				(type default)
			)
			(layer "F.Fab")
		)
		(fp_line
			(start 0.120396 0.2794)
			(end -0.12065 0.2794)
			(stroke
				(width 0.1)
				(type default)
			)
			(layer "F.Fab")
		)
		(fp_line
			(start -0.12065 0.2794)
			(end -0.12065 0.3048)
			(stroke
				(width 0.1)
				(type default)
			)
			(layer "F.Fab")
		)
		(fp_line
			(start 0.67945 0.3048)
			(end 0.120396 0.3048)
			(stroke
				(width 0.1)
				(type default)
			)
			(layer "F.Fab")
		)
		(fp_line
			(start 0.120396 0.3048)
			(end 0.120396 0.2794)
			(stroke
				(width 0.1)
				(type default)
			)
			(layer "F.Fab")
		)
		(fp_line
			(start -0.12065 0.3048)
			(end -0.67945 0.3048)
			(stroke
				(width 0.1)
				(type default)
			)
			(layer "F.Fab")
		)
		(fp_line
			(start -0.67945 0.3048)
			(end -0.67945 -0.305054)
			(stroke
				(width 0.1)
				(type default)
			)
			(layer "F.Fab")
		)
		(pad "1" smd circle
			(at -0.40005 0 90)
			(size 0 0)
			(layers "F.Cu" "F.Mask" "F.Paste")
			(net "FM_LED_ACTIVE_E1S_0_BUF")
		)
		(pad "2" smd circle
			(at 0.40005 0 90)
			(size 0 0)
			(layers "F.Cu" "F.Mask" "F.Paste")
			(net "GND")
		)
	)
	(footprint ""
		(layer "F.Cu")
		(at 426.974 -364.49 -90)
		(property "Reference" "PR601"
			(at 0 0 270)
			(layer "F.SilkS")
			(hide yes)
			(effects
				(font
					(size 1.27 1.27)
				)
			)
		)
		(property "Value" ""
			(at 0 0 270)
			(layer "F.Fab")
			(effects
				(font
					(size 1.27 1.27)
				)
			)
		)
		(duplicate_pad_numbers_are_jumpers no)
		(fp_line
			(start -0.7874 0.4064)
			(end -0.7874 -0.4064)
			(stroke
				(width 0.1524)
				(type default)
			)
			(layer "F.SilkS")
		)
		(fp_line
			(start 0.7874 0.4064)
			(end -0.7874 0.4064)
			(stroke
				(width 0.1524)
				(type default)
			)
			(layer "F.SilkS")
		)
		(fp_line
			(start -0.7874 -0.4064)
			(end 0.7874 -0.4064)
			(stroke
				(width 0.1524)
				(type default)
			)
			(layer "F.SilkS")
		)
		(fp_line
			(start 0.7874 -0.4064)
			(end 0.7874 0.4064)
			(stroke
				(width 0.1524)
				(type default)
			)
			(layer "F.SilkS")
		)
		(fp_line
			(start -0.67945 0.3048)
			(end -0.67945 -0.305054)
			(stroke
				(width 0.1)
				(type default)
			)
			(layer "F.Fab")
		)
		(fp_line
			(start -0.12065 0.3048)
			(end -0.67945 0.3048)
			(stroke
				(width 0.1)
				(type default)
			)
			(layer "F.Fab")
		)
		(fp_line
			(start 0.120396 0.3048)
			(end 0.120396 0.2794)
			(stroke
				(width 0.1)
				(type default)
			)
			(layer "F.Fab")
		)
		(fp_line
			(start 0.67945 0.3048)
			(end 0.120396 0.3048)
			(stroke
				(width 0.1)
				(type default)
			)
			(layer "F.Fab")
		)
		(fp_line
			(start -0.12065 0.2794)
			(end -0.12065 0.3048)
			(stroke
				(width 0.1)
				(type default)
			)
			(layer "F.Fab")
		)
		(fp_line
			(start 0.120396 0.2794)
			(end -0.12065 0.2794)
			(stroke
				(width 0.1)
				(type default)
			)
			(layer "F.Fab")
		)
		(fp_line
			(start -0.12065 -0.2794)
			(end 0.12065 -0.2794)
			(stroke
				(width 0.1)
				(type default)
			)
			(layer "F.Fab")
		)
		(fp_line
			(start 0.12065 -0.2794)
			(end 0.12065 -0.3048)
			(stroke
				(width 0.1)
				(type default)
			)
			(layer "F.Fab")
		)
		(fp_line
			(start 0.12065 -0.3048)
			(end 0.67945 -0.3048)
			(stroke
				(width 0.1)
				(type default)
			)
			(layer "F.Fab")
		)
		(fp_line
			(start 0.67945 -0.3048)
			(end 0.67945 0.3048)
			(stroke
				(width 0.1)
				(type default)
			)
			(layer "F.Fab")
		)
		(fp_line
			(start -0.67945 -0.305054)
			(end -0.12065 -0.305054)
			(stroke
				(width 0.1)
				(type default)
			)
			(layer "F.Fab")
		)
		(fp_line
			(start -0.12065 -0.305054)
			(end -0.12065 -0.2794)
			(stroke
				(width 0.1)
				(type default)
			)
			(layer "F.Fab")
		)
		(pad "1" smd circle
			(at -0.40005 0 270)
			(size 0 0)
			(layers "F.Cu" "F.Mask" "F.Paste")
			(net "PVDD11_S3_P0_VINSEN")
		)
		(pad "2" smd circle
			(at 0.40005 0 270)
			(size 0 0)
			(layers "F.Cu" "F.Mask" "F.Paste")
			(net "GND")
		)
	)
	(footprint ""
		(layer "F.Cu")
		(at 26.793444 -426.609256 180)
		(property "Reference" "R3282"
			(at 0 0 180)
			(layer "F.SilkS")
			(hide yes)
			(effects
				(font
					(size 1.27 1.27)
				)
			)
		)
		(property "Value" ""
			(at 0 0 180)
			(layer "F.Fab")
			(effects
				(font
					(size 1.27 1.27)
				)
			)
		)
		(duplicate_pad_numbers_are_jumpers no)
		(fp_line
			(start 0.7874 0.4064)
			(end -0.7874 0.4064)
			(stroke
				(width 0.1524)
				(type default)
			)
			(layer "F.SilkS")
		)
		(fp_line
			(start 0.7874 -0.4064)
			(end 0.7874 0.4064)
			(stroke
				(width 0.1524)
				(type default)
			)
			(layer "F.SilkS")
		)
		(fp_line
			(start -0.7874 0.4064)
			(end -0.7874 -0.4064)
			(stroke
				(width 0.1524)
				(type default)
			)
			(layer "F.SilkS")
		)
		(fp_line
			(start -0.7874 -0.4064)
			(end 0.7874 -0.4064)
			(stroke
				(width 0.1524)
				(type default)
			)
			(layer "F.SilkS")
		)
		(fp_line
			(start 0.67945 0.3048)
			(end 0.120396 0.3048)
			(stroke
				(width 0.1)
				(type default)
			)
			(layer "F.Fab")
		)
		(fp_line
			(start 0.67945 -0.3048)
			(end 0.67945 0.3048)
			(stroke
				(width 0.1)
				(type default)
			)
			(layer "F.Fab")
		)
		(fp_line
			(start 0.12065 -0.2794)
			(end 0.12065 -0.3048)
			(stroke
				(width 0.1)
				(type default)
			)
			(layer "F.Fab")
		)
		(fp_line
			(start 0.12065 -0.3048)
			(end 0.67945 -0.3048)
			(stroke
				(width 0.1)
				(type default)
			)
			(layer "F.Fab")
		)
		(fp_line
			(start 0.120396 0.3048)
			(end 0.120396 0.2794)
			(stroke
				(width 0.1)
				(type default)
			)
			(layer "F.Fab")
		)
		(fp_line
			(start 0.120396 0.2794)
			(end -0.12065 0.2794)
			(stroke
				(width 0.1)
				(type default)
			)
			(layer "F.Fab")
		)
		(fp_line
			(start -0.12065 0.3048)
			(end -0.67945 0.3048)
			(stroke
				(width 0.1)
				(type default)
			)
			(layer "F.Fab")
		)
		(fp_line
			(start -0.12065 0.2794)
			(end -0.12065 0.3048)
			(stroke
				(width 0.1)
				(type default)
			)
			(layer "F.Fab")
		)
		(fp_line
			(start -0.12065 -0.2794)
			(end 0.12065 -0.2794)
			(stroke
				(width 0.1)
				(type default)
			)
			(layer "F.Fab")
		)
		(fp_line
			(start -0.12065 -0.305054)
			(end -0.12065 -0.2794)
			(stroke
				(width 0.1)
				(type default)
			)
			(layer "F.Fab")
		)
		(fp_line
			(start -0.67945 0.3048)
			(end -0.67945 -0.305054)
			(stroke
				(width 0.1)
				(type default)
			)
			(layer "F.Fab")
		)
		(fp_line
			(start -0.67945 -0.305054)
			(end -0.12065 -0.305054)
			(stroke
				(width 0.1)
				(type default)
			)
			(layer "F.Fab")
		)
		(pad "1" smd circle
			(at -0.40005 0 180)
			(size 0 0)
			(layers "F.Cu" "F.Mask" "F.Paste")
			(net "FM_P2E_EQB0")
		)
		(pad "2" smd circle
			(at 0.40005 0 180)
			(size 0 0)
			(layers "F.Cu" "F.Mask" "F.Paste")
			(net "GND")
		)
	)
	(footprint ""
		(layer "F.Cu")
		(at 119.36857 -171.925234 90)
		(property "Reference" "PC321_SOP1_1"
			(at 0 0 90)
			(layer "F.SilkS")
			(hide yes)
			(effects
				(font
					(size 1.27 1.27)
				)
			)
		)
		(property "Value" ""
			(at 0 0 90)
			(layer "F.Fab")
			(effects
				(font
					(size 1.27 1.27)
				)
			)
		)
		(duplicate_pad_numbers_are_jumpers no)
		(fp_line
			(start 0.7874 -0.4064)
			(end 0.7874 0.4064)
			(stroke
				(width 0.1524)
				(type default)
			)
			(layer "F.SilkS")
		)
		(fp_line
			(start -0.7874 -0.4064)
			(end 0.7874 -0.4064)
			(stroke
				(width 0.1524)
				(type default)
			)
			(layer "F.SilkS")
		)
		(fp_line
			(start 0.7874 0.4064)
			(end -0.7874 0.4064)
			(stroke
				(width 0.1524)
				(type default)
			)
			(layer "F.SilkS")
		)
		(fp_line
			(start -0.7874 0.4064)
			(end -0.7874 -0.4064)
			(stroke
				(width 0.1524)
				(type default)
			)
			(layer "F.SilkS")
		)
		(fp_line
			(start -0.12065 -0.305054)
			(end -0.12065 -0.2794)
			(stroke
				(width 0.1)
				(type default)
			)
			(layer "F.Fab")
		)
		(fp_line
			(start -0.67945 -0.305054)
			(end -0.12065 -0.305054)
			(stroke
				(width 0.1)
				(type default)
			)
			(layer "F.Fab")
		)
		(fp_line
			(start 0.67945 -0.3048)
			(end 0.67945 0.3048)
			(stroke
				(width 0.1)
				(type default)
			)
			(layer "F.Fab")
		)
		(fp_line
			(start 0.12065 -0.3048)
			(end 0.67945 -0.3048)
			(stroke
				(width 0.1)
				(type default)
			)
			(layer "F.Fab")
		)
		(fp_line
			(start 0.12065 -0.2794)
			(end 0.12065 -0.3048)
			(stroke
				(width 0.1)
				(type default)
			)
			(layer "F.Fab")
		)
		(fp_line
			(start -0.12065 -0.2794)
			(end 0.12065 -0.2794)
			(stroke
				(width 0.1)
				(type default)
			)
			(layer "F.Fab")
		)
		(fp_line
			(start 0.120396 0.2794)
			(end -0.12065 0.2794)
			(stroke
				(width 0.1)
				(type default)
			)
			(layer "F.Fab")
		)
		(fp_line
			(start -0.12065 0.2794)
			(end -0.12065 0.3048)
			(stroke
				(width 0.1)
				(type default)
			)
			(layer "F.Fab")
		)
		(fp_line
			(start 0.67945 0.3048)
			(end 0.120396 0.3048)
			(stroke
				(width 0.1)
				(type default)
			)
			(layer "F.Fab")
		)
		(fp_line
			(start 0.120396 0.3048)
			(end 0.120396 0.2794)
			(stroke
				(width 0.1)
				(type default)
			)
			(layer "F.Fab")
		)
		(fp_line
			(start -0.12065 0.3048)
			(end -0.67945 0.3048)
			(stroke
				(width 0.1)
				(type default)
			)
			(layer "F.Fab")
		)
		(fp_line
			(start -0.67945 0.3048)
			(end -0.67945 -0.305054)
			(stroke
				(width 0.1)
				(type default)
			)
			(layer "F.Fab")
		)
		(pad "1" smd circle
			(at -0.40005 0 90)
			(size 0 0)
			(layers "F.Cu" "F.Mask" "F.Paste")
			(net "PVDDCR_CPU0_P1_PVCC")
		)
		(pad "2" smd circle
			(at 0.40005 0 90)
			(size 0 0)
			(layers "F.Cu" "F.Mask" "F.Paste")
			(net "GND")
		)
	)
	(footprint ""
		(layer "F.Cu")
		(at 61.0235 -111.940848)
		(property "Reference" "ME12"
			(at 0 0 0)
			(layer "F.SilkS")
			(hide yes)
			(effects
				(font
					(size 1.27 1.27)
				)
			)
		)
		(property "Value" ""
			(at 0 0 0)
			(layer "F.Fab")
			(effects
				(font
					(size 1.27 1.27)
				)
			)
		)
		(duplicate_pad_numbers_are_jumpers no)
		(zone
			(layer "F.Cu")
			(hatch none 0.5)
			(connect_pads
				(clearance 0)
			)
			(min_thickness 0.25)
			(keepout
				(tracks allowed)
				(vias allowed)
				(pads allowed)
				(copperpour allowed)
				(footprints not_allowed)
			)
			(placement
				(enabled no)
				(sheetname "")
			)
			(fill
				(thermal_gap 0.5)
				(thermal_bridge_width 0.5)
				(island_removal_mode 0)
			)
			(polygon
				(pts
					(arc
						(start 71.02348 -111.940848)
						(mid 51.02352 -111.940848)
						(end 71.02348 -111.940848)
					)
				)
			)
		)
	)
)
